# T6G (Grand Teton) — schematic netlist excerpt (pin names and nets, part order shuffled) for the footprints in the layout excerpt that follows; sources: Cadence DE-HDL packaged netlist, KiCad conversion of 04192023_DAF0TMB3IC0_F0TG_MB_C_brd_V02_OCP.brd

PR6562  Q_RES  5.6 1% CHIP  pkg 0402LF  page 363 : A = SW_P0V9_RETIMER_CPU0_BOOT2 ; B = SW_P0V9_RETIMER_CPU0_BOOT2_RC
R3728  Q_RES  2.2K 5% CHIP  pkg 0402LF  page 252 : A = P3V3_AUX ; B = SMB_LM75_1_3V3AUX_SDA

(kicad_pcb
	(version 20260206)
	(generator "pcbnew")
	(generator_version "10.0")
	(general
		(thickness 1.6)
		(legacy_teardrops no)
	)
	(paper "A4")
	(title_block
		(title "04192023_DAF0TMB3IC0_F0TG_MB_C_brd_V02_OCP.brd")
		(comment 1 "Grand Teton / footprints 485-486 of 8354")
	)
	(layers
		(0 "F.Cu" signal "TOP")
		(4 "In1.Cu" signal "GND")
		(6 "In2.Cu" signal "IN1")
		(8 "In3.Cu" signal "GND1")
		(10 "In4.Cu" signal "IN2")
		(12 "In5.Cu" signal "GND2")
		(14 "In6.Cu" signal "IN3")
		(16 "In7.Cu" signal "GND3")
		(18 "In8.Cu" signal "VCC")
		(20 "In9.Cu" signal "VCC1")
		(22 "In10.Cu" signal "GND4")
		(24 "In11.Cu" signal "IN4")
		(26 "In12.Cu" signal "GND5")
		(28 "In13.Cu" signal "IN5")
		(30 "In14.Cu" signal "GND6")
		(32 "In15.Cu" signal "IN6")
		(34 "In16.Cu" signal "GND7")
		(2 "B.Cu" signal "BOTTOM")
		(9 "F.Adhes" user "F.Adhesive")
		(11 "B.Adhes" user "B.Adhesive")
		(13 "F.Paste" user "Package Geometry/Pastemask Top")
		(15 "B.Paste" user "Package Geometry/Pastemask Bottom")
		(5 "F.SilkS" user "Ref Des/Silkscreen Top")
		(7 "B.SilkS" user "Ref Des/Silkscreen Bottom")
		(1 "F.Mask" user "Board Geometry/Soldermask Top")
		(3 "B.Mask" user "Board Geometry/Soldermask Bottom")
		(17 "Dwgs.User" user "User.Drawings")
		(19 "Cmts.User" user "User.Comments")
		(21 "Eco1.User" user "User.Eco1")
		(23 "Eco2.User" user "User.Eco2")
		(25 "Edge.Cuts" user "Board Geometry/Outline")
		(27 "Margin" user)
		(31 "F.CrtYd" user "Package Geometry/Place Bound Top")
		(29 "B.CrtYd" user "Package Geometry/Place Bound Bottom")
		(35 "F.Fab" user "Ref Des/Assembly Top")
		(33 "B.Fab" user "Ref Des/Assembly Bottom")
	)
	(footprint ""
		(layer "F.Cu")
		(at 254.592836 -117.51945)
		(property "Reference" "R3728"
			(at 0 0 0)
			(layer "F.SilkS")
			(hide yes)
			(effects
				(font
					(size 1.27 1.27)
				)
			)
		)
		(property "Value" ""
			(at 0 0 0)
			(layer "F.Fab")
			(effects
				(font
					(size 1.27 1.27)
				)
			)
		)
		(duplicate_pad_numbers_are_jumpers no)
		(fp_line
			(start -0.7874 -0.4064)
			(end 0.7874 -0.4064)
			(stroke
				(width 0.1524)
				(type default)
			)
			(layer "F.SilkS")
		)
		(fp_line
			(start -0.7874 0.4064)
			(end -0.7874 -0.4064)
			(stroke
				(width 0.1524)
				(type default)
			)
			(layer "F.SilkS")
		)
		(fp_line
			(start 0.7874 -0.4064)
			(end 0.7874 0.4064)
			(stroke
				(width 0.1524)
				(type default)
			)
			(layer "F.SilkS")
		)
		(fp_line
			(start 0.7874 0.4064)
			(end -0.7874 0.4064)
			(stroke
				(width 0.1524)
				(type default)
			)
			(layer "F.SilkS")
		)
		(fp_line
			(start -0.67945 -0.305054)
			(end -0.12065 -0.305054)
			(stroke
				(width 0.1)
				(type default)
			)
			(layer "F.Fab")
		)
		(fp_line
			(start -0.67945 0.3048)
			(end -0.67945 -0.305054)
			(stroke
				(width 0.1)
				(type default)
			)
			(layer "F.Fab")
		)
		(fp_line
			(start -0.12065 -0.305054)
			(end -0.12065 -0.2794)
			(stroke
				(width 0.1)
				(type default)
			)
			(layer "F.Fab")
		)
		(fp_line
			(start -0.12065 -0.2794)
			(end 0.12065 -0.2794)
			(stroke
				(width 0.1)
				(type default)
			)
			(layer "F.Fab")
		)
		(fp_line
			(start -0.12065 0.2794)
			(end -0.12065 0.3048)
			(stroke
				(width 0.1)
				(type default)
			)
			(layer "F.Fab")
		)
		(fp_line
			(start -0.12065 0.3048)
			(end -0.67945 0.3048)
			(stroke
				(width 0.1)
				(type default)
			)
			(layer "F.Fab")
		)
		(fp_line
			(start 0.120396 0.2794)
			(end -0.12065 0.2794)
			(stroke
				(width 0.1)
				(type default)
			)
			(layer "F.Fab")
		)
		(fp_line
			(start 0.120396 0.3048)
			(end 0.120396 0.2794)
			(stroke
				(width 0.1)
				(type default)
			)
			(layer "F.Fab")
		)
		(fp_line
			(start 0.12065 -0.3048)
			(end 0.67945 -0.3048)
			(stroke
				(width 0.1)
				(type default)
			)
			(layer "F.Fab")
		)
		(fp_line
			(start 0.12065 -0.2794)
			(end 0.12065 -0.3048)
			(stroke
				(width 0.1)
				(type default)
			)
			(layer "F.Fab")
		)
		(fp_line
			(start 0.67945 -0.3048)
			(end 0.67945 0.3048)
			(stroke
				(width 0.1)
				(type default)
			)
			(layer "F.Fab")
		)
		(fp_line
			(start 0.67945 0.3048)
			(end 0.120396 0.3048)
			(stroke
				(width 0.1)
				(type default)
			)
			(layer "F.Fab")
		)
		(pad "1" smd circle
			(at -0.40005 0)
			(size 0 0)
			(layers "F.Cu" "F.Mask" "F.Paste")
			(net "P3V3_AUX")
		)
		(pad "2" smd circle
			(at 0.40005 0)
			(size 0 0)
			(layers "F.Cu" "F.Mask" "F.Paste")
			(net "SMB_LM75_1_3V3AUX_SDA")
		)
	)
	(footprint ""
		(layer "F.Cu")
		(at 455.115676 -401.709128 90)
		(property "Reference" "PR6562"
			(at 0 0 90)
			(layer "F.SilkS")
			(hide yes)
			(effects
				(font
					(size 1.27 1.27)
				)
			)
		)
		(property "Value" ""
			(at 0 0 90)
			(layer "F.Fab")
			(effects
				(font
					(size 1.27 1.27)
				)
			)
		)
		(duplicate_pad_numbers_are_jumpers no)
		(fp_line
			(start 0.7874 -0.4064)
			(end 0.7874 0.4064)
			(stroke
				(width 0.1524)
				(type default)
			)
			(layer "F.SilkS")
		)
		(fp_line
			(start -0.7874 -0.4064)
			(end 0.7874 -0.4064)
			(stroke
				(width 0.1524)
				(type default)
			)
			(layer "F.SilkS")
		)
		(fp_line
			(start 0.7874 0.4064)
			(end -0.7874 0.4064)
			(stroke
				(width 0.1524)
				(type default)
			)
			(layer "F.SilkS")
		)
		(fp_line
			(start -0.7874 0.4064)
			(end -0.7874 -0.4064)
			(stroke
				(width 0.1524)
				(type default)
			)
			(layer "F.SilkS")
		)
		(fp_line
			(start -0.12065 -0.305054)
			(end -0.12065 -0.2794)
			(stroke
				(width 0.1)
				(type default)
			)
			(layer "F.Fab")
		)
		(fp_line
			(start -0.67945 -0.305054)
			(end -0.12065 -0.305054)
			(stroke
				(width 0.1)
				(type default)
			)
			(layer "F.Fab")
		)
		(fp_line
			(start 0.67945 -0.3048)
			(end 0.67945 0.3048)
			(stroke
				(width 0.1)
				(type default)
			)
			(layer "F.Fab")
		)
		(fp_line
			(start 0.12065 -0.3048)
			(end 0.67945 -0.3048)
			(stroke
				(width 0.1)
				(type default)
			)
			(layer "F.Fab")
		)
		(fp_line
			(start 0.12065 -0.2794)
			(end 0.12065 -0.3048)
			(stroke
				(width 0.1)
				(type default)
			)
			(layer "F.Fab")
		)
		(fp_line
			(start -0.12065 -0.2794)
			(end 0.12065 -0.2794)
			(stroke
				(width 0.1)
				(type default)
			)
			(layer "F.Fab")
		)
		(fp_line
			(start 0.120396 0.2794)
			(end -0.12065 0.2794)
			(stroke
				(width 0.1)
				(type default)
			)
			(layer "F.Fab")
		)
		(fp_line
			(start -0.12065 0.2794)
			(end -0.12065 0.3048)
			(stroke
				(width 0.1)
				(type default)
			)
			(layer "F.Fab")
		)
		(fp_line
			(start 0.67945 0.3048)
			(end 0.120396 0.3048)
			(stroke
				(width 0.1)
				(type default)
			)
			(layer "F.Fab")
		)
		(fp_line
			(start 0.120396 0.3048)
			(end 0.120396 0.2794)
			(stroke
				(width 0.1)
				(type default)
			)
			(layer "F.Fab")
		)
		(fp_line
			(start -0.12065 0.3048)
			(end -0.67945 0.3048)
			(stroke
				(width 0.1)
				(type default)
			)
			(layer "F.Fab")
		)
		(fp_line
			(start -0.67945 0.3048)
			(end -0.67945 -0.305054)
			(stroke
				(width 0.1)
				(type default)
			)
			(layer "F.Fab")
		)
		(pad "1" smd circle
			(at -0.40005 0 90)
			(size 0 0)
			(layers "F.Cu" "F.Mask" "F.Paste")
			(net "SW_P0V9_RETIMER_CPU0_BOOT2")
		)
		(pad "2" smd circle
			(at 0.40005 0 90)
			(size 0 0)
			(layers "F.Cu" "F.Mask" "F.Paste")
			(net "SW_P0V9_RETIMER_CPU0_BOOT2_RC")
		)
	)
)
